# T6G (Grand Teton) — schematic netlist excerpt (pin names and nets, part order shuffled) for the footprints in the layout excerpt that follows; sources: Cadence DE-HDL packaged netlist, KiCad conversion of 04192023_DAF0TMB3IC0_F0TG_MB_C_brd_V02_OCP.brd

C91  Q_CAP  12PF 50V 5% C0G  pkg C0402  page 176 : A = XTAL_USB_CPU0_HUB1_XIN ; B = GND
PC479_1  Q_CAP  0.1UF 25V 10% X7R  pkg 0402  page 194 : A = SW_P12V_AUX_PVDDCR_CPU0_P0_FLT ; B = GND

(kicad_pcb
	(version 20260206)
	(generator "pcbnew")
	(generator_version "10.0")
	(general
		(thickness 1.6)
		(legacy_teardrops no)
	)
	(paper "A4")
	(title_block
		(title "04192023_DAF0TMB3IC0_F0TG_MB_C_brd_V02_OCP.brd")
		(comment 1 "Grand Teton / footprints 4801-4802 of 8354")
	)
	(layers
		(0 "F.Cu" signal "TOP")
		(4 "In1.Cu" signal "GND")
		(6 "In2.Cu" signal "IN1")
		(8 "In3.Cu" signal "GND1")
		(10 "In4.Cu" signal "IN2")
		(12 "In5.Cu" signal "GND2")
		(14 "In6.Cu" signal "IN3")
		(16 "In7.Cu" signal "GND3")
		(18 "In8.Cu" signal "VCC")
		(20 "In9.Cu" signal "VCC1")
		(22 "In10.Cu" signal "GND4")
		(24 "In11.Cu" signal "IN4")
		(26 "In12.Cu" signal "GND5")
		(28 "In13.Cu" signal "IN5")
		(30 "In14.Cu" signal "GND6")
		(32 "In15.Cu" signal "IN6")
		(34 "In16.Cu" signal "GND7")
		(2 "B.Cu" signal "BOTTOM")
		(9 "F.Adhes" user "F.Adhesive")
		(11 "B.Adhes" user "B.Adhesive")
		(13 "F.Paste" user "Package Geometry/Pastemask Top")
		(15 "B.Paste" user "Package Geometry/Pastemask Bottom")
		(5 "F.SilkS" user "Ref Des/Silkscreen Top")
		(7 "B.SilkS" user "Ref Des/Silkscreen Bottom")
		(1 "F.Mask" user "Board Geometry/Soldermask Top")
		(3 "B.Mask" user "Board Geometry/Soldermask Bottom")
		(17 "Dwgs.User" user "User.Drawings")
		(19 "Cmts.User" user "User.Comments")
		(21 "Eco1.User" user "User.Eco1")
		(23 "Eco2.User" user "User.Eco2")
		(25 "Edge.Cuts" user "Board Geometry/Outline")
		(27 "Margin" user)
		(31 "F.CrtYd" user "Package Geometry/Place Bound Top")
		(29 "B.CrtYd" user "Package Geometry/Place Bound Bottom")
		(35 "F.Fab" user "Ref Des/Assembly Top")
		(33 "B.Fab" user "Ref Des/Assembly Bottom")
	)
	(footprint ""
		(layer "F.Cu")
		(at 363.793278 -171.64431)
		(property "Reference" "PC479_1"
			(at 0 0 0)
			(layer "F.SilkS")
			(hide yes)
			(effects
				(font
					(size 1.27 1.27)
				)
			)
		)
		(property "Value" ""
			(at 0 0 0)
			(layer "F.Fab")
			(effects
				(font
					(size 1.27 1.27)
				)
			)
		)
		(duplicate_pad_numbers_are_jumpers no)
		(fp_line
			(start -0.7874 -0.4064)
			(end 0.7874 -0.4064)
			(stroke
				(width 0.1524)
				(type default)
			)
			(layer "F.SilkS")
		)
		(fp_line
			(start -0.7874 0.4064)
			(end -0.7874 -0.4064)
			(stroke
				(width 0.1524)
				(type default)
			)
			(layer "F.SilkS")
		)
		(fp_line
			(start 0.7874 -0.4064)
			(end 0.7874 0.4064)
			(stroke
				(width 0.1524)
				(type default)
			)
			(layer "F.SilkS")
		)
		(fp_line
			(start 0.7874 0.4064)
			(end -0.7874 0.4064)
			(stroke
				(width 0.1524)
				(type default)
			)
			(layer "F.SilkS")
		)
		(fp_line
			(start -0.67945 -0.305054)
			(end -0.12065 -0.305054)
			(stroke
				(width 0.1)
				(type default)
			)
			(layer "F.Fab")
		)
		(fp_line
			(start -0.67945 0.3048)
			(end -0.67945 -0.305054)
			(stroke
				(width 0.1)
				(type default)
			)
			(layer "F.Fab")
		)
		(fp_line
			(start -0.12065 -0.305054)
			(end -0.12065 -0.2794)
			(stroke
				(width 0.1)
				(type default)
			)
			(layer "F.Fab")
		)
		(fp_line
			(start -0.12065 -0.2794)
			(end 0.12065 -0.2794)
			(stroke
				(width 0.1)
				(type default)
			)
			(layer "F.Fab")
		)
		(fp_line
			(start -0.12065 0.2794)
			(end -0.12065 0.3048)
			(stroke
				(width 0.1)
				(type default)
			)
			(layer "F.Fab")
		)
		(fp_line
			(start -0.12065 0.3048)
			(end -0.67945 0.3048)
			(stroke
				(width 0.1)
				(type default)
			)
			(layer "F.Fab")
		)
		(fp_line
			(start 0.120396 0.2794)
			(end -0.12065 0.2794)
			(stroke
				(width 0.1)
				(type default)
			)
			(layer "F.Fab")
		)
		(fp_line
			(start 0.120396 0.3048)
			(end 0.120396 0.2794)
			(stroke
				(width 0.1)
				(type default)
			)
			(layer "F.Fab")
		)
		(fp_line
			(start 0.12065 -0.3048)
			(end 0.67945 -0.3048)
			(stroke
				(width 0.1)
				(type default)
			)
			(layer "F.Fab")
		)
		(fp_line
			(start 0.12065 -0.2794)
			(end 0.12065 -0.3048)
			(stroke
				(width 0.1)
				(type default)
			)
			(layer "F.Fab")
		)
		(fp_line
			(start 0.67945 -0.3048)
			(end 0.67945 0.3048)
			(stroke
				(width 0.1)
				(type default)
			)
			(layer "F.Fab")
		)
		(fp_line
			(start 0.67945 0.3048)
			(end 0.120396 0.3048)
			(stroke
				(width 0.1)
				(type default)
			)
			(layer "F.Fab")
		)
		(pad "1" smd circle
			(at -0.40005 0)
			(size 0 0)
			(layers "F.Cu" "F.Mask" "F.Paste")
			(net "SW_P12V_AUX_PVDDCR_CPU0_P0_FLT")
		)
		(pad "2" smd circle
			(at 0.40005 0)
			(size 0 0)
			(layers "F.Cu" "F.Mask" "F.Paste")
			(net "GND")
		)
	)
	(footprint ""
		(layer "F.Cu")
		(at 126.58979 -27.863546 -90)
		(property "Reference" "C91"
			(at 0 0 270)
			(layer "F.SilkS")
			(hide yes)
			(effects
				(font
					(size 1.27 1.27)
				)
			)
		)
		(property "Value" ""
			(at 0 0 270)
			(layer "F.Fab")
			(effects
				(font
					(size 1.27 1.27)
				)
			)
		)
		(duplicate_pad_numbers_are_jumpers no)
		(fp_line
			(start -0.7874 0.4064)
			(end -0.7874 -0.4064)
			(stroke
				(width 0.1524)
				(type default)
			)
			(layer "F.SilkS")
		)
		(fp_line
			(start 0.7874 0.4064)
			(end -0.7874 0.4064)
			(stroke
				(width 0.1524)
				(type default)
			)
			(layer "F.SilkS")
		)
		(fp_line
			(start -0.7874 -0.4064)
			(end 0.7874 -0.4064)
			(stroke
				(width 0.1524)
				(type default)
			)
			(layer "F.SilkS")
		)
		(fp_line
			(start 0.7874 -0.4064)
			(end 0.7874 0.4064)
			(stroke
				(width 0.1524)
				(type default)
			)
			(layer "F.SilkS")
		)
		(fp_line
			(start -0.67945 0.3048)
			(end -0.67945 -0.305054)
			(stroke
				(width 0.1)
				(type default)
			)
			(layer "F.Fab")
		)
		(fp_line
			(start -0.12065 0.3048)
			(end -0.67945 0.3048)
			(stroke
				(width 0.1)
				(type default)
			)
			(layer "F.Fab")
		)
		(fp_line
			(start 0.120396 0.3048)
			(end 0.120396 0.2794)
			(stroke
				(width 0.1)
				(type default)
			)
			(layer "F.Fab")
		)
		(fp_line
			(start 0.67945 0.3048)
			(end 0.120396 0.3048)
			(stroke
				(width 0.1)
				(type default)
			)
			(layer "F.Fab")
		)
		(fp_line
			(start -0.12065 0.2794)
			(end -0.12065 0.3048)
			(stroke
				(width 0.1)
				(type default)
			)
			(layer "F.Fab")
		)
		(fp_line
			(start 0.120396 0.2794)
			(end -0.12065 0.2794)
			(stroke
				(width 0.1)
				(type default)
			)
			(layer "F.Fab")
		)
		(fp_line
			(start -0.12065 -0.2794)
			(end 0.12065 -0.2794)
			(stroke
				(width 0.1)
				(type default)
			)
			(layer "F.Fab")
		)
		(fp_line
			(start 0.12065 -0.2794)
			(end 0.12065 -0.3048)
			(stroke
				(width 0.1)
				(type default)
			)
			(layer "F.Fab")
		)
		(fp_line
			(start 0.12065 -0.3048)
			(end 0.67945 -0.3048)
			(stroke
				(width 0.1)
				(type default)
			)
			(layer "F.Fab")
		)
		(fp_line
			(start 0.67945 -0.3048)
			(end 0.67945 0.3048)
			(stroke
				(width 0.1)
				(type default)
			)
			(layer "F.Fab")
		)
		(fp_line
			(start -0.67945 -0.305054)
			(end -0.12065 -0.305054)
			(stroke
				(width 0.1)
				(type default)
			)
			(layer "F.Fab")
		)
		(fp_line
			(start -0.12065 -0.305054)
			(end -0.12065 -0.2794)
			(stroke
				(width 0.1)
				(type default)
			)
			(layer "F.Fab")
		)
		(pad "1" smd circle
			(at -0.40005 0 270)
			(size 0 0)
			(layers "F.Cu" "F.Mask" "F.Paste")
			(net "XTAL_USB_CPU0_HUB1_XIN")
		)
		(pad "2" smd circle
			(at 0.40005 0 270)
			(size 0 0)
			(layers "F.Cu" "F.Mask" "F.Paste")
			(net "GND")
		)
	)
)
